FILE_TYPE = CONNECTIVITY;
{Allegro Design Entry HDL 16.6-p007 (v16-6-112F) 10/10/2012}
"PAGE_NUMBER" = 223;
0"NC";
1"PVCCIO_CPU1\g";
2"GND\g";
3"GND\g";
4"GND\g";
5"GND\g";
6"GND\g";
7"GND\g";
8"P3V3_STBY\g";
9"GND\g";
10"GND\g";
11"GND\g";
12"GND\g";
13"P3V3_STBY\g";
14"PVCCIO_CPU1\g";
15"ISENSE_PVDDQ_GHJ_PH1_IMON";
16"VR_PVDDQ_GHJ_PWM1";
17"SVID_ALERT1_CPU1_R_N";
18"SVID_DIO1_CPU1_R";
19"SMB_VR_STBY_LVC3_SCL";
20"PWRGD_PVDDQ_GHJ_R";
21"IRQ_PVDDQ_GHJ_VRHOT_LVT3_R_N";
22"VR_PVDDQ_GHJ_VDD";
23"SVID_CLK_PVDDQ_GHJ";
24"VR_PVDDQ_GHJ_VREN";
25"ISENSE_PVDDQ_GHJ_PH2_IMON";
26"VR_PVDDQ_GHJ_AIREF1";
27"VR_PVDDQ_GHJ_AIREF2";
28"VR_PVDDQ_GHJ_VINSEN";
29"VR_PVDDQ_GHJ_AIINSEN";
30"A_TSENSE_PVDDQ_GHJ";
31"VSENSE_PVDDQ_GHJ_N";
32"VR_PVDDQ_GHJ_VD12";
33"SVID_CLK1_CPU1_R";
34"PWRGD_PVDDQ_GHJ";
35"TP_PVDDQ_GHJ_MP2";
36"IRQ_PVDDQ_GHJ_VRHOT_LVT3_N";
37"SMB_VR_STBY_LVC3_SDA";
38"PU_VR_PVDDQ_GHJ_FAULT1";
39"VR_PVDDQ_GHJ_VD12";
40"VR_PVDDQ_GHJ_PWM2";
41"VR_PVDDQ_GHJ_XADDR1";
42"VR_PVDDQ_GHJ_XADDR2";
43"VR_PVDDQ_GHJ_AVSP";
44"SVID_VDIO_PVDDQ_GHJ";
45"TP_PVDDQ_GHJ_MP1";
46"SVID_ALERT_PVDDQ_GHJ";
47"VSENSE_PVDDQ_GHJ_P";
48"FM_PVDDQ_GHJ_EN";
%"CAP"
"1","(-1450,575)","0","mstr_discrete","I12";
;
VOLTAGE"50V"
PART_NUMBER"A36096-050"
VALUE"220PF"
PACK_TYPE"0402LF"
MATERIAL"X7R"
LOCATION"C1G16"
TOLERANCE"10%"
CDS_SEC"1"
CDS_LIB"mstr_discrete"
NO_XNET_CONNECTION"1"
ROOM"VDDQ_GHJ_PWR_VR"
SEC_TYPE"0402LF"
CDS_LOCATION"C1G16"
SEC"1";
"A"
$PN"1"43;
"B"
$PN"2"31;
%"RES"
"1","(-1725,725)","0","mstr_discrete","I13";
;
WATTAGE"1/16W"
MATERIAL"CHIP"
PACK_TYPE"0402"
TOLERANCE"1%"
VALUE"10.0"
PART_NUMBER"G21796-066"
LOCATION"R1G5"
CDS_SEC"1"
CDS_LIB"mstr_discrete"
CDS_LOCATION"R1G5"
ROOM"VDDQ_GHJ_PWR_VR"
NO_XNET_CONNECTION"1"
SEC_TYPE"0402"
SEC"1";
"B"
$PN"2"43;
"A"
$PN"1"47;
%"RES"
"1","(-1500,1150)","0","mstr_discrete","I14";
;
PACK_TYPE"0402"
VALUE"0.0"
WATTAGE"1/16W"
MATERIAL"CHIP"
TOLERANCE"5%"
PART_NUMBER"G21497-005"
LOCATION"R9U7"
CDS_SEC"1"
SEC_TYPE"0402"
SEC"1"
ROOM"PVCCIN_CPU0_VR"
CDS_LOCATION"R9U7"
CDS_LIB"mstr_discrete";
"B"
$PN"2"24;
"A"
$PN"1"48;
%"SC22P50V2JN-4GP"
"1","(-1100,2275)","1","w_hdl","I15";
;
TYPE"NPO"
TOLERANCE"5%"
ATTRIBUTE"22PF"
LOCATION"CF19"
PACK_SIZE"0402"
VALUE"SC22P50V2JN-4GP"
GROUP"POWER_FAIR"
RATED"50V"
CDS_SEC"1"
$SEC"1"
CDS_LOCATION"CF19"
CDS_LMAN_SYM_OUTLINE"-50,25,50,-25"
CDS_LIB"w_hdl"
PART_NUMBER"78.22034.1FL"
PACK_TYPE"SMD-BCG";
"2"
$PN"2"15;
"1"
$PN"1"26;
%"RES"
"1","(-1100,2450)","0","mstr_discrete","I16";
;
PART_NUMBER"G85996-004"
TOLERANCE"0.1%"
VALUE"1.0K"
LOCATION"RF19"
PACK_TYPE"0402"
MATERIAL"CHIP"
WATTAGE"1/16W"
GROUP"POWER_FAIR"
FAIR_SS"064.9530D.M001"
CDS_SEC"1"
CDS_LOCATION"RF19"
SEC_TYPE"0402"
SEC"1"
CDS_LIB"mstr_discrete"
ROOM"SB";
"B"
$PN"2"15;
"A"
$PN"1"26;
%"SC22P50V2JN-4GP"
"1","(-225,2275)","1","w_hdl","I17";
;
GROUP"POWER_FAIR"
BOM_SS"NOPOP"
RATED"50V"
VALUE"SC22P50V2JN-4GP"
TOLERANCE"5%"
ATTRIBUTE"22PF"
TYPE"NPO"
PACK_SIZE"0402"
LOCATION"CF20"
CDS_LIB"w_hdl"
CDS_LMAN_SYM_OUTLINE"-50,25,50,-25"
PART_NUMBER"78.22034.1FL"
PACK_TYPE"SMD-BCG"
CDS_LOCATION"CF20"
$SEC"1"
CDS_SEC"1";
"2"
$PN"2"25;
"1"
$PN"1"27;
%"RES"
"1","(-225,2625)","0","mstr_discrete","I18";
;
PACK_TYPE"0402"
MATERIAL"CHIP"
WATTAGE"1/16W"
PART_NUMBER"G21796-009"
LOCATION"R1G7"
TOLERANCE"1%"
VALUE"150.0"
CDS_SEC"1"
CDS_LIB"mstr_discrete"
ROOM"VDDQ_GHJ_PWR_VR"
CDS_LOCATION"R1G7"
SEC"1"
SEC_TYPE"0402";
"B"
$PN"2"23;
"A"
$PN"1"33;
%"RES"
"1","(-225,2450)","0","mstr_discrete","I19";
;
GROUP"POWER_FAIR"
BOM_SS"NOPOP"
TOLERANCE"0.1%"
VALUE"1.0K"
PART_NUMBER"G85996-004"
MATERIAL"CHIP"
PACK_TYPE"0402"
WATTAGE"1/16W"
LOCATION"RF20"
CDS_LIB"mstr_discrete"
ROOM"SB"
SEC_TYPE"0402"
SEC"1"
CDS_LOCATION"RF20"
CDS_SEC"1";
"B"
$PN"2"25;
"A"
$PN"1"27;
%"PVCCIO_CPU1"
"1","(-625,3575)","0","mstr_symbols","I21";
;
CDS_LIB"mstr_symbols"
VOLTAGE"1.1V"
BODY_TYPE"PLUMBING"
HDL_POWER"PVCCIO_CPU1";
"G\NAC"1;
%"GND"
"1","(3375,-425)","0","mstr_symbols","I22";
;
VOLTAGE"0"
SIZE"1B"
CDS_LIB"mstr_symbols"
ROOM"VDDQ_GHJ_PWR_VR"
BODY_TYPE"PLUMBING"
HDL_POWER"GND";
"A\NAC"2;
%"GND"
"1","(4025,-525)","0","mstr_symbols","I23";
;
VOLTAGE"0"
SIZE"1B"
CDS_LIB"mstr_symbols"
ROOM"VDDQ_GHJ_PWR_VR"
BODY_TYPE"PLUMBING"
HDL_POWER"GND";
"A\NAC"3;
%"GND"
"1","(100,-300)","0","mstr_symbols","I24";
;
ROOM"VDDQ_GHJ_PWR_VR"
SIZE"1B"
CDS_LIB"mstr_symbols"
VOLTAGE"0"
BODY_TYPE"PLUMBING"
HDL_POWER"GND";
"A\NAC"4;
%"GND"
"1","(275,-500)","0","mstr_symbols","I25";
;
CDS_LIB"mstr_symbols"
VOLTAGE"0"
SIZE"1B"
ROOM"VDDQ_GHJ_PWR_VR"
BODY_TYPE"PLUMBING"
HDL_POWER"GND";
"A\NAC"5;
%"CAP"
"1","(100,400)","2","mstr_discrete","I27";
;
LOCATION"C1G24"
MATERIAL"X7R"
VOLTAGE"50V"
VALUE"220PF"
TOLERANCE"10%"
PART_NUMBER"A36096-050"
PACK_TYPE"0402LF"
CDS_SEC"1"
CDS_LIB"mstr_discrete"
SEC_TYPE"0402LF"
ROOM"VDDQ_GHJ_PWR_VR"
SEC"1"
CDS_LOCATION"C1G24";
"A"
$PN"1"30;
"B"
$PN"2"4;
%"GND"
"1","(175,500)","0","mstr_symbols","I28";
;
ROOM"VDDQ_GHJ_PWR_VR"
VOLTAGE"0"
CDS_LIB"mstr_symbols"
SIZE"1B"
BODY_TYPE"PLUMBING"
HDL_POWER"GND";
"A\NAC"6;
%"GND"
"1","(625,-500)","0","mstr_symbols","I29";
;
CDS_LIB"mstr_symbols"
VOLTAGE"0"
ROOM"VDDQ_GHJ_PWR_VR"
SIZE"1B"
BODY_TYPE"PLUMBING"
HDL_POWER"GND";
"A\NAC"7;
%"RES"
"2","(175,3075)","0","mstr_discrete","I31";
;
VALUE"100.0K"
PACK_TYPE"0402"
TOLERANCE"1%"
WATTAGE"1/16W"
MATERIAL"EMPTY"
PART_NUMBER"G21796-010"
LOCATION"R9U8"
CDS_SEC"1"
SEC_TYPE"0402"
SEC"1"
CDS_LIB"mstr_discrete"
CDS_LOCATION"R9U8"
ROOM"BMC"
BOM_COST"SM_CONTROLLER";
"A"
$PN"1"8;
"B"
$PN"2"24;
%"RES"
"2","(900,3100)","0","mstr_discrete","I32";
;
TOLERANCE"5%"
WATTAGE"1/16W"
MATERIAL"CHIP"
PACK_TYPE"0402"
VALUE"0.0"
LOCATION"R9U10"
PART_NUMBER"G21497-005"
CDS_SEC"1"
CDS_LIB"mstr_discrete"
CDS_LOCATION"R9U10"
ROOM"VDDQ_GHJ_PWR_VR"
SEC"1"
SEC_TYPE"0402";
"A"
$PN"1"8;
"B"
$PN"2"22;
%"P3V3_STBY"
"1","(900,3425)","0","mstr_symbols","I33";
;
VOLTAGE"3.3V"
CDS_LIB"mstr_symbols"
SIZE"1B"
BODY_TYPE"PLUMBING"
HDL_POWER"P3V3_STBY";
"G\NAC"8;
%"GND"
"1","(1100,2550)","0","mstr_symbols","I34";
;
VOLTAGE"0"
SIZE"1B"
CDS_LIB"mstr_symbols"
ROOM"VDDQ_GHJ_PWR_VR"
BODY_TYPE"PLUMBING"
HDL_POWER"GND";
"A\NAC"9;
%"CAP_A"
"1","(1100,2750)","0","dev_discrete","I35";
;
VOLTAGE"16V"
TOLERANCE"10%"
LOCATION"C1G25"
PACK_TYPE"0402V"
PART_NUMBER"A36096-030"
MATERIAL"X7R"
VALUE"0.1UF"
SEC_TYPE"0402V"
SEC"1"
CDS_SEC"1"
ROOM"VDDQ_GHJ_PWR_VR"
CDS_LOCATION"C1G25"
CDS_LIB"dev_discrete";
"B"
$PN"2"9;
"A"
$PN"1"22;
%"CAP_A"
"1","(1600,2750)","0","dev_discrete","I36";
;
VOLTAGE"6.3V"
TOLERANCE"10%"
MATERIAL"X6S"
PART_NUMBER"D97712-004"
PACK_TYPE"0402V"
VALUE"1.0UF"
LOCATION"C1G27"
CDS_SEC"1"
SEC_TYPE"0402V"
SEC"1"
CDS_LOCATION"C1G27"
CDS_LIB"dev_discrete"
ROOM"VDDQ_GHJ_PWR_VR";
"B"
$PN"2"10;
"A"
$PN"1"22;
%"GND"
"1","(1600,2550)","0","mstr_symbols","I37";
;
ROOM"VDDQ_GHJ_PWR_VR"
VOLTAGE"0"
CDS_LIB"mstr_symbols"
SIZE"1B"
BODY_TYPE"PLUMBING"
HDL_POWER"GND";
"A\NAC"10;
%"GND"
"1","(2075,475)","0","mstr_symbols","I38";
;
ROOM"VDDQ_GHJ_PWR_VR"
VOLTAGE"0"
SIZE"1B"
CDS_LIB"mstr_symbols"
BODY_TYPE"PLUMBING"
HDL_POWER"GND";
"A\NAC"11;
%"GND"
"1","(3050,350)","0","mstr_symbols","I39";
;
ROOM"VDDQ_GHJ_PWR_VR"
VOLTAGE"0"
CDS_LIB"mstr_symbols"
SIZE"1B"
BODY_TYPE"PLUMBING"
HDL_POWER"GND";
"A\NAC"12;
%"CAP"
"1","(3050,650)","0","mstr_discrete","I40";
;
VALUE"1000PF"
LOCATION"C1G21"
PACK_TYPE"0402LF"
VOLTAGE"50V"
TOLERANCE"10%"
PART_NUMBER"A36096-046"
MATERIAL"X7R"
CDS_SEC"1"
CDS_LIB"mstr_discrete"
SEC_TYPE"0402LF"
SEC"1"
CDS_LOCATION"C1G21"
ROOM"VDDQ_GHJ_PWR_VR";
"A"
$PN"1"20;
"B"
$PN"2"12;
%"RES"
"1","(2850,1350)","0","mstr_discrete","I41";
;
TOLERANCE"5%"
WATTAGE"1/16W"
PART_NUMBER"G21497-005"
LOCATION"R1G10"
PACK_TYPE"0402"
VALUE"0.0"
MATERIAL"CHIP"
CDS_SEC"1"
CDS_LOCATION"R1G10"
SEC_TYPE"0402"
SEC"1"
ROOM"VDDQ_GHJ_PWR_VR"
CDS_LIB"mstr_discrete";
"B"
$PN"2"18;
"A"
$PN"1"44;
%"CAP_A"
"1","(3375,-225)","0","dev_discrete","I43";
;
LOCATION"C1G22"
MATERIAL"X7R"
PACK_TYPE"0402V"
PART_NUMBER"A36096-030"
TOLERANCE"10%"
VALUE"0.1UF"
VOLTAGE"16V"
CDS_LOCATION"C1G22"
CDS_LIB"dev_discrete"
SEC_TYPE"0402V"
CDS_SEC"1"
ROOM"VDDQ_GHJ_PWR_VR"
SEC"1";
"B"
$PN"2"2;
"A"
$PN"1"32;
%"CAP_A"
"1","(4025,-225)","0","dev_discrete","I44";
;
TOLERANCE"10%"
LOCATION"C1G23"
VALUE"1.0UF"
MATERIAL"X6S"
PACK_TYPE"0402V"
PART_NUMBER"D97712-004"
VOLTAGE"6.3V"
CDS_SEC"1"
SEC_TYPE"0402V"
SEC"1"
ROOM"VDDQ_GHJ_PWR_VR"
CDS_LIB"dev_discrete"
CDS_LOCATION"C1G23";
"B"
$PN"2"3;
"A"
$PN"1"32;
%"RES"
"1","(3250,1500)","0","mstr_discrete","I45";
;
PART_NUMBER"G21497-005"
TOLERANCE"5%"
VALUE"0.0"
MATERIAL"EMPTY"
LOCATION"R12W32"
WATTAGE"1/16W"
PACK_TYPE"0402"
CDS_SEC"1"
CDS_LOCATION"R12W32"
CDS_LIB"mstr_discrete"
SEC"1"
ROOM"NV_DIMM"
SEC_TYPE"0402"
BOM_COST"MEM_NV";
"B"
$PN"2"34;
"A"
$PN"1"45;
%"RES"
"2","(2400,2750)","0","mstr_discrete","I48";
;
MATERIAL"CHIP"
PACK_TYPE"0402"
VALUE"1.00K"
LOCATION"R1G16"
TOLERANCE"1%"
WATTAGE"1/16W"
PART_NUMBER"G21796-026"
CDS_SEC"1"
CDS_LIB"mstr_discrete"
CDS_LOCATION"R1G16"
ROOM"VDDQ_GHJ_PWR_VR"
SEC_TYPE"0402"
SEC"1";
"A"
$PN"1"13;
"B"
$PN"2"20;
%"RES"
"2","(2100,2750)","0","mstr_discrete","I49";
;
PACK_TYPE"0402"
PART_NUMBER"G21796-026"
LOCATION"R1G11"
VALUE"1.00K"
WATTAGE"1/16W"
TOLERANCE"1%"
MATERIAL"CHIP"
CDS_SEC"1"
ROOM"RQ_PVDDQ_GHJ_VRHOT_LVT3_N"
SEC_TYPE"0402"
SEC"1"
CDS_LOCATION"R1G11"
CDS_LIB"mstr_discrete";
"A"
$PN"1"13;
"B"
$PN"2"21;
%"RES"
"1","(2875,2050)","0","mstr_discrete","I50";
;
WATTAGE"1/16W"
MATERIAL"CHIP"
LOCATION"R1G9"
VALUE"0.0"
PART_NUMBER"G21497-005"
TOLERANCE"5%"
PACK_TYPE"0402"
CDS_SEC"1"
ROOM"VDDQ_GHJ_PWR_VR"
CDS_LOCATION"R1G9"
CDS_LIB"mstr_discrete"
SEC"1"
SEC_TYPE"0402";
"B"
$PN"2"17;
"A"
$PN"1"46;
%"P3V3_STBY"
"1","(2475,3450)","0","mstr_symbols","I52";
;
CDS_LIB"mstr_symbols"
SIZE"1B"
VOLTAGE"3.3V"
BODY_TYPE"PLUMBING"
HDL_POWER"P3V3_STBY";
"G\NAC"13;
%"RES"
"1","(3250,1900)","0","mstr_discrete","I53";
;
LOCATION"R12W33"
VALUE"0.0"
WATTAGE"1/16W"
MATERIAL"EMPTY"
TOLERANCE"5%"
PACK_TYPE"0402"
PART_NUMBER"G21497-005"
CDS_SEC"1"
CDS_LOCATION"R12W33"
BOM_COST"MEM_NV"
SEC_TYPE"0402"
ROOM"NV_DIMM"
SEC"1"
CDS_LIB"mstr_discrete";
"B"
$PN"2"34;
"A"
$PN"1"35;
%"RES"
"1","(3275,2200)","0","mstr_discrete","I54";
;
CDS_SEC"1"
POP"NOPOP"
MATERIAL"CHIP"
LOCATION"R1G12"
PART_NUMBER"G21796-250"
VALUE"22.1"
TOLERANCE"1.0%"
WATTAGE"1/16W"
PACK_TYPE"0402"
CDS_LIB"mstr_discrete"
ROOM"VDDQ_GHJ_PWR_VR"
CDS_LOCATION"R1G12"
SEC"1"
SEC_TYPE"0402";
"B"
$PN"2"34;
"A"
$PN"1"20;
%"RES"
"1","(3175,2100)","0","mstr_discrete","I55";
;
PART_NUMBER"G21796-074"
TOLERANCE"1%"
VALUE"33.2"
LOCATION"R1G8"
WATTAGE"1/16W"
MATERIAL"CHIP"
PACK_TYPE"0402"
CDS_SEC"1"
CDS_LOCATION"R1G8"
CDS_LIB"mstr_discrete"
SEC"1"
SEC_TYPE"0402";
"B"
$PN"2"36;
"A"
$PN"1"21;
%"RES"
"2","(4100,2425)","0","mstr_discrete","I57";
;
MATERIAL"CHIP"
PART_NUMBER"G21796-017"
PACK_TYPE"0402"
LOCATION"R9U3"
VALUE"100.0"
TOLERANCE"1%"
WATTAGE"1/16W"
CDS_LIB"mstr_discrete"
CDS_LOCATION"R9U3"
ROOM"VDDQ_GHJ_PWR_VR"
SEC"1"
SEC_TYPE"0402"
CDS_SEC"1";
"A"
$PN"1"14;
"B"
$PN"2"18;
%"PVCCIO_CPU1"
"1","(4100,2625)","0","mstr_symbols","I58";
;
VOLTAGE"1.1V"
CDS_LIB"mstr_symbols"
BODY_TYPE"PLUMBING"
HDL_POWER"PVCCIO_CPU1";
"G\NAC"14;
%"PXM1310B"
"2","(1500,1450)","0","mstr_controller","I69";
;
PART_NUMBER"H89186-001"
MATERIAL"IC"
LOCATION"EU1G2"
CDS_SEC"1"
CDS_LMAN_SYM_OUTLINE"-400,900,400,-900"
CDS_LIB"mstr_controller"
CDS_LOCATION"EU1G2"
PACK_TYPE"QFN"
SEC_TYPE"QFN"
SEC"1";
"MP2"
$PN"18"35;
"THPAD"
$PN"41"11;
"BPWM1"
$PN"1"0;
"APWM1"
$PN"5"16;
"APWM2"
$PN"4"40;
"APWM3"
$PN"3"0;
"SDA"
$PN"6"37;
"SCL"
$PN"7"19;
"VCLK"
$PN"15"23;
"VDIO"
$PN"16"44;
"RESET_N \B"
$PN"8"0;
"XADDR1"
$PN"36"41;
"AISEN3"
$PN"26"0;
"AIREF3"
$PN"25"0;
"XADDR2"
$PN"33"42;
"AISEN2"
$PN"24"25;
"AIREF2"
$PN"23"27;
"ATSEN"
$PN"35"30;
"AISEN1"
$PN"22"15;
"AIREF1"
$PN"21"26;
"VDD"
$PN"39"22;
"BTSEN"
$PN"34"0;
"BISEN1"
$PN"32"6;
"BIREF1"
$PN"31"0;
"DNC<0>"
$PN"2"0;
"DNC<1>"
$PN"28"0;
"VRHOT_N \B"
$PN"11"21;
"PINALRT_N \B"
$PN"12"0;
"VALRT_N \B"
$PN"17"46;
"AVSEN"
$PN"19"43;
"AVREF"
$PN"20"31;
"BVSEN"
$PN"29"0;
"BVREF"
$PN"30"0;
"VINSEN"
$PN"37"28;
"VD12"
$PN"40"39;
"GND"
$PN"27"11;
"IINSEN"
$PN"38"29;
"AVRRDY"
$PN"9"20;
"AVREN"
$PN"10"24;
"MP0"
$PN"13"38;
"MP1"
$PN"14"45;
%"RES"
"2","(-625,3000)","0","mstr_discrete","I70";
;
PACK_TYPE"0402"
LOCATION"R9U4"
VALUE"49.9"
WATTAGE"1/16W"
PART_NUMBER"G21796-047"
MATERIAL"CHIP"
TOLERANCE"1%"
CDS_LOCATION"R9U4"
CDS_LIB"mstr_discrete"
ROOM"VDDQ_KLM_PWR_VR"
SEC"1"
SEC_TYPE"0402"
CDS_SEC"1";
"A"
$PN"1"1;
"B"
$PN"2"33;
%"RES"
"2","(275,-250)","0","mstr_discrete","I73";
;
PART_NUMBER"G21796-297"
VALUE"5.36K"
MATERIAL"CHIP"
LOCATION"R1G23"
TOLERANCE"1.0%"
WATTAGE"1/16W"
POP"NOPOP"
PACK_TYPE"0402"
CDS_LOCATION"R1G23"
CDS_SEC"1"
SEC"1"
CDS_LIB"mstr_discrete"
ROOM"VDDQ_GHJ_PWR_VR"
SEC_TYPE"0402";
"A"
$PN"1"41;
"B"
$PN"2"5;
%"RES"
"2","(625,-250)","0","mstr_discrete","I74";
;
MATERIAL"CHIP"
PART_NUMBER"G21796-043"
PACK_TYPE"0402"
WATTAGE"1/16W"
VALUE"3.16K"
LOCATION"R1G22"
TOLERANCE"1%"
SEC_TYPE"0402"
SEC"1"
ROOM"PVCCIN_CPU1_VR"
CDS_LIB"mstr_discrete"
CDS_SEC"1"
CDS_LOCATION"R1G22";
"A"
$PN"1"42;
"B"
$PN"2"7;
%"RES"
"1","(3250,1550)","0","mstr_discrete","I75";
;
WATTAGE"1/16W"
VALUE"0.0"
PART_NUMBER"G21497-005"
TOLERANCE"5%"
LOCATION"R12W31"
PACK_TYPE"0402"
SEC"1"
SEC_TYPE"0402"
ROOM"CPU0"
MATERIAL"CHIP"
BOM_COST"PROC_SIDEBAND"
CDS_LIB"mstr_discrete"
CDS_SEC"1"
CDS_LOCATION"R12W31";
"B"
$PN"2"34;
"A"
$PN"1"38;
%"RES"
"2","(3550,2750)","0","mstr_discrete","I76";
;
CDS_SEC"1"
CDS_LOCATION"R1G6"
MATERIAL"CHIP"
WATTAGE"1/16W"
TOLERANCE"1.0%"
VALUE"2.26K"
LOCATION"R1G6"
PART_NUMBER"G21796-311"
PACK_TYPE"0402"
SKU"B"
ROOM"SMBUS"
BOM_COST"SM_CONTROLLER"
CDS_LIB"mstr_discrete"
SEC"1"
SEC_TYPE"0402";
"A"
$PN"1"13;
"B"
$PN"2"34;
END.
